# T6G (Grand Teton) — schematic netlist excerpt (pin names and nets, part order shuffled) for the footprints in the layout excerpt that follows; sources: Cadence DE-HDL packaged netlist, KiCad conversion of 04192023_DAF0TMB3IC0_F0TG_MB_C_brd_V02_OCP.brd

R3071  Q_RES  130 1% CHIP  pkg 0402LF  page 254 : A = LED_PWRGD_P1V8_AUX ; B = P3V3_AUX
R1496  Q_RES  33 5% CHIP  pkg 0402LF  page 151 : A = SMB_SCM_2_R1_SDA ; B = SMB_SCM_2_R2_SDA
C6679  Q_CAP_DIFFBUS  DIFF BUS_0.22UF 6.3V 20% X6S  pkg C0201  page 330 : \1\ = P5E_CPU1_P1_TX_BUF_C_DP<9> ; \2\ = P5E_CPU1_P1_TX_BUF_DP<9>

(kicad_pcb
	(version 20260206)
	(generator "pcbnew")
	(generator_version "10.0")
	(general
		(thickness 1.6)
		(legacy_teardrops no)
	)
	(paper "A4")
	(title_block
		(title "04192023_DAF0TMB3IC0_F0TG_MB_C_brd_V02_OCP.brd")
		(comment 1 "Grand Teton / footprints 7882-7884 of 8354")
	)
	(layers
		(0 "F.Cu" signal "TOP")
		(4 "In1.Cu" signal "GND")
		(6 "In2.Cu" signal "IN1")
		(8 "In3.Cu" signal "GND1")
		(10 "In4.Cu" signal "IN2")
		(12 "In5.Cu" signal "GND2")
		(14 "In6.Cu" signal "IN3")
		(16 "In7.Cu" signal "GND3")
		(18 "In8.Cu" signal "VCC")
		(20 "In9.Cu" signal "VCC1")
		(22 "In10.Cu" signal "GND4")
		(24 "In11.Cu" signal "IN4")
		(26 "In12.Cu" signal "GND5")
		(28 "In13.Cu" signal "IN5")
		(30 "In14.Cu" signal "GND6")
		(32 "In15.Cu" signal "IN6")
		(34 "In16.Cu" signal "GND7")
		(2 "B.Cu" signal "BOTTOM")
		(9 "F.Adhes" user "F.Adhesive")
		(11 "B.Adhes" user "B.Adhesive")
		(13 "F.Paste" user "Package Geometry/Pastemask Top")
		(15 "B.Paste" user "Package Geometry/Pastemask Bottom")
		(5 "F.SilkS" user "Ref Des/Silkscreen Top")
		(7 "B.SilkS" user "Ref Des/Silkscreen Bottom")
		(1 "F.Mask" user "Board Geometry/Soldermask Top")
		(3 "B.Mask" user "Board Geometry/Soldermask Bottom")
		(17 "Dwgs.User" user "User.Drawings")
		(19 "Cmts.User" user "User.Comments")
		(21 "Eco1.User" user "User.Eco1")
		(23 "Eco2.User" user "User.Eco2")
		(25 "Edge.Cuts" user "Board Geometry/Outline")
		(27 "Margin" user)
		(31 "F.CrtYd" user "Package Geometry/Place Bound Top")
		(29 "B.CrtYd" user "Package Geometry/Place Bound Bottom")
		(35 "F.Fab" user "Ref Des/Assembly Top")
		(33 "B.Fab" user "Ref Des/Assembly Bottom")
	)
	(footprint ""
		(layer "B.Cu")
		(at 20.32 -367.919)
		(property "Reference" "R1496"
			(at 0 0 0)
			(layer "B.SilkS")
			(hide yes)
			(effects
				(font
					(size 1.27 1.27)
				)
				(justify mirror)
			)
		)
		(property "Value" ""
			(at 0 0 0)
			(layer "B.Fab")
			(effects
				(font
					(size 1.27 1.27)
				)
				(justify mirror)
			)
		)
		(duplicate_pad_numbers_are_jumpers no)
		(fp_line
			(start -0.7874 -0.4064)
			(end -0.7874 0.4064)
			(stroke
				(width 0.1524)
				(type default)
			)
			(layer "B.SilkS")
		)
		(fp_line
			(start -0.7874 0.4064)
			(end 0.7874 0.4064)
			(stroke
				(width 0.1524)
				(type default)
			)
			(layer "B.SilkS")
		)
		(fp_line
			(start 0.7874 -0.4064)
			(end -0.7874 -0.4064)
			(stroke
				(width 0.1524)
				(type default)
			)
			(layer "B.SilkS")
		)
		(fp_line
			(start 0.7874 0.4064)
			(end 0.7874 -0.4064)
			(stroke
				(width 0.1524)
				(type default)
			)
			(layer "B.SilkS")
		)
		(fp_line
			(start -0.67945 -0.3048)
			(end -0.67945 0.3048)
			(stroke
				(width 0.1)
				(type default)
			)
			(layer "B.Fab")
		)
		(fp_line
			(start -0.67945 0.3048)
			(end -0.120396 0.3048)
			(stroke
				(width 0.1)
				(type default)
			)
			(layer "B.Fab")
		)
		(fp_line
			(start -0.12065 -0.3048)
			(end -0.67945 -0.3048)
			(stroke
				(width 0.1)
				(type default)
			)
			(layer "B.Fab")
		)
		(fp_line
			(start -0.12065 -0.2794)
			(end -0.12065 -0.3048)
			(stroke
				(width 0.1)
				(type default)
			)
			(layer "B.Fab")
		)
		(fp_line
			(start -0.120396 0.2794)
			(end 0.12065 0.2794)
			(stroke
				(width 0.1)
				(type default)
			)
			(layer "B.Fab")
		)
		(fp_line
			(start -0.120396 0.3048)
			(end -0.120396 0.2794)
			(stroke
				(width 0.1)
				(type default)
			)
			(layer "B.Fab")
		)
		(fp_line
			(start 0.12065 -0.305054)
			(end 0.12065 -0.2794)
			(stroke
				(width 0.1)
				(type default)
			)
			(layer "B.Fab")
		)
		(fp_line
			(start 0.12065 -0.2794)
			(end -0.12065 -0.2794)
			(stroke
				(width 0.1)
				(type default)
			)
			(layer "B.Fab")
		)
		(fp_line
			(start 0.12065 0.2794)
			(end 0.12065 0.3048)
			(stroke
				(width 0.1)
				(type default)
			)
			(layer "B.Fab")
		)
		(fp_line
			(start 0.12065 0.3048)
			(end 0.67945 0.3048)
			(stroke
				(width 0.1)
				(type default)
			)
			(layer "B.Fab")
		)
		(fp_line
			(start 0.67945 -0.305054)
			(end 0.12065 -0.305054)
			(stroke
				(width 0.1)
				(type default)
			)
			(layer "B.Fab")
		)
		(fp_line
			(start 0.67945 0.3048)
			(end 0.67945 -0.305054)
			(stroke
				(width 0.1)
				(type default)
			)
			(layer "B.Fab")
		)
		(pad "1" smd circle
			(at 0.40005 0 180)
			(size 0 0)
			(layers "B.Cu" "B.Mask" "B.Paste")
			(net "SMB_SCM_2_R1_SDA")
		)
		(pad "2" smd circle
			(at -0.40005 0 180)
			(size 0 0)
			(layers "B.Cu" "B.Mask" "B.Paste")
			(net "SMB_SCM_2_R2_SDA")
		)
	)
	(footprint ""
		(layer "B.Cu")
		(at 77.783944 -408.517344 90)
		(property "Reference" "C6679"
			(at 0 0 90)
			(layer "B.SilkS")
			(hide yes)
			(effects
				(font
					(size 1.27 1.27)
				)
				(justify mirror)
			)
		)
		(property "Value" ""
			(at 0 0 90)
			(layer "B.Fab")
			(effects
				(font
					(size 1.27 1.27)
				)
				(justify mirror)
			)
		)
		(duplicate_pad_numbers_are_jumpers no)
		(fp_line
			(start 0.299974 -0.150114)
			(end -0.299974 -0.150114)
			(stroke
				(width 0.1)
				(type default)
			)
			(layer "B.Fab")
		)
		(fp_line
			(start -0.299974 -0.150114)
			(end -0.299974 0.150114)
			(stroke
				(width 0.1)
				(type default)
			)
			(layer "B.Fab")
		)
		(fp_line
			(start 0.299974 0.150114)
			(end 0.299974 -0.150114)
			(stroke
				(width 0.1)
				(type default)
			)
			(layer "B.Fab")
		)
		(fp_line
			(start -0.299974 0.150114)
			(end 0.299974 0.150114)
			(stroke
				(width 0.1)
				(type default)
			)
			(layer "B.Fab")
		)
		(pad "1" smd rect
			(at 0.2667 0 270)
			(size 0.3048 0.381)
			(layers "B.Cu" "B.Mask" "B.Paste")
			(net "P5E_CPU1_P1_TX_BUF_C_DP<9>")
		)
		(pad "2" smd rect
			(at -0.2667 0 270)
			(size 0.3048 0.381)
			(layers "B.Cu" "B.Mask" "B.Paste")
			(net "P5E_CPU1_P1_TX_BUF_DP<9>")
		)
	)
	(footprint ""
		(layer "B.Cu")
		(at 318.539876 -66.708782 90)
		(property "Reference" "R3071"
			(at 0 0 90)
			(layer "B.SilkS")
			(hide yes)
			(effects
				(font
					(size 1.27 1.27)
				)
				(justify mirror)
			)
		)
		(property "Value" ""
			(at 0 0 90)
			(layer "B.Fab")
			(effects
				(font
					(size 1.27 1.27)
				)
				(justify mirror)
			)
		)
		(duplicate_pad_numbers_are_jumpers no)
		(fp_line
			(start 0.7874 -0.4064)
			(end -0.7874 -0.4064)
			(stroke
				(width 0.1524)
				(type default)
			)
			(layer "B.SilkS")
		)
		(fp_line
			(start -0.7874 -0.4064)
			(end -0.7874 0.4064)
			(stroke
				(width 0.1524)
				(type default)
			)
			(layer "B.SilkS")
		)
		(fp_line
			(start 0.7874 0.4064)
			(end 0.7874 -0.4064)
			(stroke
				(width 0.1524)
				(type default)
			)
			(layer "B.SilkS")
		)
		(fp_line
			(start -0.7874 0.4064)
			(end 0.7874 0.4064)
			(stroke
				(width 0.1524)
				(type default)
			)
			(layer "B.SilkS")
		)
		(fp_line
			(start 0.67945 -0.305054)
			(end 0.12065 -0.305054)
			(stroke
				(width 0.1)
				(type default)
			)
			(layer "B.Fab")
		)
		(fp_line
			(start 0.12065 -0.305054)
			(end 0.12065 -0.2794)
			(stroke
				(width 0.1)
				(type default)
			)
			(layer "B.Fab")
		)
		(fp_line
			(start -0.12065 -0.3048)
			(end -0.67945 -0.3048)
			(stroke
				(width 0.1)
				(type default)
			)
			(layer "B.Fab")
		)
		(fp_line
			(start -0.67945 -0.3048)
			(end -0.67945 0.3048)
			(stroke
				(width 0.1)
				(type default)
			)
			(layer "B.Fab")
		)
		(fp_line
			(start 0.12065 -0.2794)
			(end -0.12065 -0.2794)
			(stroke
				(width 0.1)
				(type default)
			)
			(layer "B.Fab")
		)
		(fp_line
			(start -0.12065 -0.2794)
			(end -0.12065 -0.3048)
			(stroke
				(width 0.1)
				(type default)
			)
			(layer "B.Fab")
		)
		(fp_line
			(start 0.12065 0.2794)
			(end 0.12065 0.3048)
			(stroke
				(width 0.1)
				(type default)
			)
			(layer "B.Fab")
		)
		(fp_line
			(start -0.120396 0.2794)
			(end 0.12065 0.2794)
			(stroke
				(width 0.1)
				(type default)
			)
			(layer "B.Fab")
		)
		(fp_line
			(start 0.67945 0.3048)
			(end 0.67945 -0.305054)
			(stroke
				(width 0.1)
				(type default)
			)
			(layer "B.Fab")
		)
		(fp_line
			(start 0.12065 0.3048)
			(end 0.67945 0.3048)
			(stroke
				(width 0.1)
				(type default)
			)
			(layer "B.Fab")
		)
		(fp_line
			(start -0.120396 0.3048)
			(end -0.120396 0.2794)
			(stroke
				(width 0.1)
				(type default)
			)
			(layer "B.Fab")
		)
		(fp_line
			(start -0.67945 0.3048)
			(end -0.120396 0.3048)
			(stroke
				(width 0.1)
				(type default)
			)
			(layer "B.Fab")
		)
		(pad "1" smd circle
			(at 0.40005 0 270)
			(size 0 0)
			(layers "B.Cu" "B.Mask" "B.Paste")
			(net "LED_PWRGD_P1V8_AUX")
		)
		(pad "2" smd circle
			(at -0.40005 0 270)
			(size 0 0)
			(layers "B.Cu" "B.Mask" "B.Paste")
			(net "P3V3_AUX")
		)
	)
)
